(kicad_pcb
	(version 20240108)
	(generator "pcbnew")
	(generator_version "8.0")
	(general
		(thickness 1.62)
		(legacy_teardrops no)
	)
	(paper "A4")
	(title_block
		(title "Jetson Orin Baseboard")
		(date "2025-03-12")
		(rev "1.3.4")
		(company "Antmicro Ltd")
		(comment 1 "www.antmicro.com")
		(comment 9 "footprints 68-71 of 677")
	)
	(layers
		(0 "F.Cu" signal)
		(1 "In1.Cu" signal)
		(2 "In2.Cu" signal)
		(3 "In3.Cu" signal)
		(4 "In4.Cu" jumper)
		(5 "In5.Cu" signal)
		(6 "In6.Cu" signal)
		(31 "B.Cu" signal)
		(32 "B.Adhes" user "B.Adhesive")
		(33 "F.Adhes" user "F.Adhesive")
		(34 "B.Paste" user)
		(35 "F.Paste" user)
		(36 "B.SilkS" user "B.Silkscreen")
		(37 "F.SilkS" user "F.Silkscreen")
		(38 "B.Mask" user)
		(39 "F.Mask" user)
		(40 "Dwgs.User" user "User.Drawings")
		(41 "Cmts.User" user "User.Comments")
		(42 "Eco1.User" user "User.Eco1")
		(43 "Eco2.User" user "User.Eco2")
		(44 "Edge.Cuts" user)
		(45 "Margin" user)
		(46 "B.CrtYd" user "B.Courtyard")
		(47 "F.CrtYd" user "F.Courtyard")
		(48 "B.Fab" user)
		(49 "F.Fab" user)
	)
	(footprint "antmicro-footprints:XDFN-2_1x0.60mm"
		(layer "F.Cu")
		(at 136.27 91.26 90)
		(property "Reference" "D19"
			(at -0.3 0.4 0)
			(layer "F.SilkS")
			(effects
				(font
					(size 0.7 0.7)
					(thickness 0.15)
				)
				(justify left bottom)
			)
		)
		(property "Value" "TPD1E0B04_XDFN-2"
			(at 0 1.5 90)
			(layer "F.Fab")
			(effects
				(font
					(size 0.7 0.7)
					(thickness 0.15)
				)
				(justify left bottom)
			)
		)
		(property "Footprint" "antmicro-footprints:XDFN-2_1x0.60mm"
			(at 0 0 90)
			(layer "F.Fab")
			(hide yes)
			(effects
				(font
					(size 1.27 1.27)
					(thickness 0.15)
				)
			)
		)
		(property "Datasheet" "https://www.ti.com/general/docs/suppproductinfo.tsp?distId=26&gotoUrl=https://www.ti.com/lit/gpn/tpd1e0b04"
			(at 0 0 90)
			(layer "F.Fab")
			(hide yes)
			(effects
				(font
					(size 1.27 1.27)
					(thickness 0.15)
				)
			)
		)
		(property "MPN" "TPD1E0B04DPYR"
			(at 227.53 -45.01 0)
			(layer "F.Fab")
			(hide yes)
			(effects
				(font
					(size 1 1)
					(thickness 0.15)
				)
			)
		)
		(property "Manufacturer" "Texas Instruments"
			(at 227.53 -45.01 0)
			(layer "F.Fab")
			(hide yes)
			(effects
				(font
					(size 1 1)
					(thickness 0.15)
				)
			)
		)
		(property "Author" "Antmicro"
			(at 227.53 -45.01 0)
			(layer "F.Fab")
			(hide yes)
			(effects
				(font
					(size 1 1)
					(thickness 0.15)
				)
			)
		)
		(property "License" "Apache-2.0"
			(at 227.53 -45.01 0)
			(layer "F.Fab")
			(hide yes)
			(effects
				(font
					(size 1 1)
					(thickness 0.15)
				)
			)
		)
		(sheetname "Peripherals")
		(sheetfile "peripherals.kicad_sch")
		(attr smd)
		(fp_rect
			(start -0.725 -0.475)
			(end 0.725 0.475)
			(stroke
				(width 0.05)
				(type solid)
			)
			(fill none)
			(layer "F.CrtYd")
		)
		(fp_rect
			(start -0.55 -0.35)
			(end 0.55 0.35)
			(stroke
				(width 0.15)
				(type solid)
			)
			(fill none)
			(layer "F.Fab")
		)
		(fp_text user "${REFERENCE}"
			(at -0.8 3.2 90)
			(layer "F.Fab")
			(hide yes)
			(effects
				(font
					(size 0.7 0.7)
					(thickness 0.15)
				)
				(justify left bottom)
			)
		)
		(fp_text user "Author: Antmicro"
			(at -0.8 4.4 90)
			(layer "F.Fab")
			(hide yes)
			(effects
				(font
					(size 0.7 0.7)
					(thickness 0.15)
				)
				(justify left bottom)
			)
		)
		(fp_text user "License: Apache-2.0"
			(at -0.8 5.6 90)
			(layer "F.Fab")
			(hide yes)
			(effects
				(font
					(size 0.7 0.7)
					(thickness 0.15)
				)
				(justify left bottom)
			)
		)
		(pad "1" smd roundrect
			(at -0.351 0 90)
			(size 0.3 0.5)
			(layers "F.Cu" "F.Paste" "F.Mask")
			(roundrect_rratio 0.25)
			(net 416 "/Peripherals/USBSS2_TX_CONN_N")
			(pinfunction "C")
			(pintype "passive")
		)
		(pad "2" smd roundrect
			(at 0.349 0 90)
			(size 0.3 0.5)
			(layers "F.Cu" "F.Paste" "F.Mask")
			(roundrect_rratio 0.25)
			(net 1 "GND")
			(pinfunction "A")
			(pintype "passive")
		)
	)
	(footprint "antmicro-footprints:C_0402_1005Metric"
		(layer "F.Cu")
		(at 136.35 82.95 180)
		(descr "Capacitor SMD 0402")
		(tags "capacitor SMD 0402")
		(property "Reference" "C112"
			(at 3.6 -0.4 180)
			(layer "F.SilkS")
			(effects
				(font
					(size 0.7 0.7)
					(thickness 0.15)
				)
				(justify left bottom)
			)
		)
		(property "Value" "C_220n_0402"
			(at 0 1.4 180)
			(layer "F.Fab")
			(effects
				(font
					(size 0.7 0.7)
					(thickness 0.15)
				)
				(justify left bottom)
			)
		)
		(property "Footprint" "antmicro-footprints:C_0402_1005Metric"
			(at 0 0 180)
			(layer "F.Fab")
			(hide yes)
			(effects
				(font
					(size 1.27 1.27)
					(thickness 0.15)
				)
			)
		)
		(property "Datasheet" "https://www.yageo.com/en/Chart/Download/pdf/CC0402KRX5R6BB224"
			(at 0 0 180)
			(layer "F.Fab")
			(hide yes)
			(effects
				(font
					(size 1.27 1.27)
					(thickness 0.15)
				)
			)
		)
		(property "Author" "Antmicro"
			(at 272.7 165.9 0)
			(layer "F.Fab")
			(hide yes)
			(effects
				(font
					(size 1 1)
					(thickness 0.15)
				)
			)
		)
		(property "Dielectric" ""
			(at 272.7 165.9 0)
			(layer "F.Fab")
			(hide yes)
			(effects
				(font
					(size 1 1)
					(thickness 0.15)
				)
			)
		)
		(property "License" "Apache-2.0"
			(at 272.7 165.9 0)
			(layer "F.Fab")
			(hide yes)
			(effects
				(font
					(size 1 1)
					(thickness 0.15)
				)
			)
		)
		(property "MPN" "CC0402KRX5R6BB224"
			(at 272.7 165.9 0)
			(layer "F.Fab")
			(hide yes)
			(effects
				(font
					(size 1 1)
					(thickness 0.15)
				)
			)
		)
		(property "Manufacturer" "YAGEO"
			(at 272.7 165.9 0)
			(layer "F.Fab")
			(hide yes)
			(effects
				(font
					(size 1 1)
					(thickness 0.15)
				)
			)
		)
		(property "Val" "220n"
			(at 272.7 165.9 0)
			(layer "F.Fab")
			(hide yes)
			(effects
				(font
					(size 1 1)
					(thickness 0.15)
				)
			)
		)
		(property "Voltage" ""
			(at 272.7 165.9 0)
			(layer "F.Fab")
			(hide yes)
			(effects
				(font
					(size 1 1)
					(thickness 0.15)
				)
			)
		)
		(sheetname "Peripherals")
		(sheetfile "peripherals.kicad_sch")
		(attr smd)
		(fp_rect
			(start -0.925 -0.47)
			(end 0.925 0.47)
			(stroke
				(width 0.05)
				(type default)
			)
			(fill none)
			(layer "F.CrtYd")
		)
		(fp_line
			(start 0.504 0.248)
			(end -0.494 0.248)
			(stroke
				(width 0.15)
				(type solid)
			)
			(layer "F.Fab")
		)
		(fp_line
			(start 0.504 -0.25)
			(end 0.504 0.248)
			(stroke
				(width 0.15)
				(type solid)
			)
			(layer "F.Fab")
		)
		(fp_line
			(start -0.494 0.248)
			(end -0.494 -0.25)
			(stroke
				(width 0.15)
				(type solid)
			)
			(layer "F.Fab")
		)
		(fp_line
			(start -0.494 -0.25)
			(end 0.504 -0.25)
			(stroke
				(width 0.15)
				(type solid)
			)
			(layer "F.Fab")
		)
		(fp_text user "${REFERENCE}"
			(at -0.932 3.168 180)
			(layer "F.Fab")
			(hide yes)
			(effects
				(font
					(size 0.7 0.7)
					(thickness 0.15)
				)
				(justify left bottom)
			)
		)
		(fp_text user "License: Apache-2.0"
			(at -0.932 5.17 180)
			(layer "F.Fab")
			(hide yes)
			(effects
				(font
					(size 0.7 0.7)
					(thickness 0.15)
				)
				(justify left bottom)
			)
		)
		(fp_text user "Author: Antmicro"
			(at -0.932 4.17 180)
			(layer "F.Fab")
			(hide yes)
			(effects
				(font
					(size 0.7 0.7)
					(thickness 0.15)
				)
				(justify left bottom)
			)
		)
		(pad "1" smd roundrect
			(at -0.48 0 180)
			(size 0.59 0.64)
			(layers "F.Cu" "F.Paste" "F.Mask")
			(roundrect_rratio 0.25)
			(net 415 "/Peripherals/PCIE2_TX1_CONN_N")
			(pintype "passive")
		)
		(pad "2" smd roundrect
			(at 0.48 0 180)
			(size 0.59 0.64)
			(layers "F.Cu" "F.Paste" "F.Mask")
			(roundrect_rratio 0.25)
			(net 357 "PCIE2_TX1_N")
			(pintype "passive")
		)
	)
	(footprint "antmicro-footprints:C_0603_1608Metric_EIA"
		(layer "F.Cu")
		(at 71.25 91.67 -90)
		(descr "Capacitor SMD 0603, IPC-7351 Density Level A")
		(tags "Capacitor 0603")
		(property "Reference" "C126"
			(at -6.406396 -14.35 -90)
			(layer "F.SilkS")
			(effects
				(font
					(size 0.7 0.7)
					(thickness 0.15)
				)
				(justify left bottom)
			)
		)
		(property "Value" "C_22u_16V_0603"
			(at -1.42757 1.770288 -90)
			(layer "F.Fab")
			(effects
				(font
					(size 0.7 0.7)
					(thickness 0.15)
				)
				(justify left bottom)
			)
		)
		(property "Footprint" "antmicro-footprints:C_0603_1608Metric_EIA"
			(at 0 0 -90)
			(layer "F.Fab")
			(hide yes)
			(effects
				(font
					(size 1.27 1.27)
					(thickness 0.15)
				)
			)
		)
		(property "Datasheet" "https://product.samsungsem.com/mlcc/CL10A226MO7JZN.do"
			(at 0 0 -90)
			(layer "F.Fab")
			(hide yes)
			(effects
				(font
					(size 1.27 1.27)
					(thickness 0.15)
				)
			)
		)
		(property "Description" "SMD Multilayer Ceramic Capacitor"
			(at 0 0 -90)
			(layer "F.Fab")
			(hide yes)
			(effects
				(font
					(size 1.27 1.27)
					(thickness 0.15)
				)
			)
		)
		(property "Manufacturer" "Samsung Electro-Mechanics"
			(at 0 0 -90)
			(unlocked yes)
			(layer "F.Fab")
			(hide yes)
			(effects
				(font
					(size 1 1)
					(thickness 0.15)
				)
			)
		)
		(property "MPN" "CL10A226MO7JZNC"
			(at 0 0 -90)
			(unlocked yes)
			(layer "F.Fab")
			(hide yes)
			(effects
				(font
					(size 1 1)
					(thickness 0.15)
				)
			)
		)
		(property "Val" "22u"
			(at 0 0 -90)
			(unlocked yes)
			(layer "F.Fab")
			(hide yes)
			(effects
				(font
					(size 1 1)
					(thickness 0.15)
				)
			)
		)
		(property "License" "Apache-2.0"
			(at 0 0 -90)
			(unlocked yes)
			(layer "F.Fab")
			(hide yes)
			(effects
				(font
					(size 1 1)
					(thickness 0.15)
				)
			)
		)
		(property "Author" "Antmicro"
			(at 0 0 -90)
			(unlocked yes)
			(layer "F.Fab")
			(hide yes)
			(effects
				(font
					(size 1 1)
					(thickness 0.15)
				)
			)
		)
		(property "Voltage" "16V"
			(at 0 0 -90)
			(unlocked yes)
			(layer "F.Fab")
			(hide yes)
			(effects
				(font
					(size 1 1)
					(thickness 0.15)
				)
			)
		)
		(property "Dielectric" ""
			(at 0 0 -90)
			(unlocked yes)
			(layer "F.Fab")
			(hide yes)
			(effects
				(font
					(size 1 1)
					(thickness 0.15)
				)
			)
		)
		(sheetname "Supply")
		(sheetfile "supply.kicad_sch")
		(attr smd)
		(fp_line
			(start -0.15 0.55)
			(end 0.15 0.55)
			(stroke
				(width 0.15)
				(type solid)
			)
			(layer "F.SilkS")
		)
		(fp_line
			(start -0.15 -0.55)
			(end 0.15 -0.55)
			(stroke
				(width 0.15)
				(type solid)
			)
			(layer "F.SilkS")
		)
		(fp_rect
			(start -1.25 -0.65)
			(end 1.25 0.65)
			(stroke
				(width 0.05)
				(type solid)
			)
			(fill none)
			(layer "F.CrtYd")
		)
		(fp_rect
			(start -0.8 -0.45)
			(end 0.8 0.45)
			(stroke
				(width 0.15)
				(type solid)
			)
			(fill none)
			(layer "F.Fab")
		)
		(fp_text user "License: Apache-2.0"
			(at -1.682 5.895 -90)
			(layer "F.Fab")
			(hide yes)
			(effects
				(font
					(size 0.7 0.7)
					(thickness 0.15)
				)
				(justify left bottom)
			)
		)
		(fp_text user "${REFERENCE}"
			(at -1.682 3.895 -90)
			(layer "F.Fab")
			(hide yes)
			(effects
				(font
					(size 0.7 0.7)
					(thickness 0.15)
				)
				(justify left bottom)
			)
		)
		(fp_text user "Author: Antmicro"
			(at -1.682 4.894 -90)
			(layer "F.Fab")
			(hide yes)
			(effects
				(font
					(size 0.7 0.7)
					(thickness 0.15)
				)
				(justify left bottom)
			)
		)
		(pad "1" smd roundrect
			(at -0.7 0 270)
			(size 0.8 1.1)
			(layers "F.Cu" "F.Paste" "F.Mask")
			(roundrect_rratio 0.2)
			(net 1 "GND")
			(pintype "passive")
		)
		(pad "2" smd roundrect
			(at 0.7 0 270)
			(size 0.8 1.1)
			(layers "F.Cu" "F.Paste" "F.Mask")
			(roundrect_rratio 0.2)
			(net 641 "/Supply/3V3_OUT")
			(pintype "passive")
		)
	)
	(footprint "antmicro-footprints:C_0402_1005Metric"
		(layer "F.Cu")
		(at 69.9 108.7 180)
		(descr "Capacitor SMD 0402")
		(tags "capacitor SMD 0402")
		(property "Reference" "C55"
			(at 1 -1.33 180)
			(layer "F.SilkS")
			(effects
				(font
					(size 0.7 0.7)
					(thickness 0.15)
				)
				(justify left bottom)
			)
		)
		(property "Value" "C_100n_0402"
			(at 0 1.4 180)
			(layer "F.Fab")
			(effects
				(font
					(size 0.7 0.7)
					(thickness 0.15)
				)
				(justify left bottom)
			)
		)
		(property "Footprint" "antmicro-footprints:C_0402_1005Metric"
			(at 0 0 180)
			(layer "F.Fab")
			(hide yes)
			(effects
				(font
					(size 1.27 1.27)
					(thickness 0.15)
				)
			)
		)
		(property "Datasheet" "https://www.murata.com/products/productdetail?partno=GRM155R61H104KE14%23"
			(at 0 0 180)
			(layer "F.Fab")
			(hide yes)
			(effects
				(font
					(size 1.27 1.27)
					(thickness 0.15)
				)
			)
		)
		(property "Author" "Antmicro"
			(at 139.8 217.4 0)
			(layer "F.Fab")
			(hide yes)
			(effects
				(font
					(size 1 1)
					(thickness 0.15)
				)
			)
		)
		(property "Dielectric" "X5R"
			(at 139.8 217.4 0)
			(layer "F.Fab")
			(hide yes)
			(effects
				(font
					(size 1 1)
					(thickness 0.15)
				)
			)
		)
		(property "License" "Apache-2.0"
			(at 139.8 217.4 0)
			(layer "F.Fab")
			(hide yes)
			(effects
				(font
					(size 1 1)
					(thickness 0.15)
				)
			)
		)
		(property "MPN" "GRM155R61H104KE14D"
			(at 139.8 217.4 0)
			(layer "F.Fab")
			(hide yes)
			(effects
				(font
					(size 1 1)
					(thickness 0.15)
				)
			)
		)
		(property "Manufacturer" "Murata"
			(at 139.8 217.4 0)
			(layer "F.Fab")
			(hide yes)
			(effects
				(font
					(size 1 1)
					(thickness 0.15)
				)
			)
		)
		(property "Val" "100n"
			(at 139.8 217.4 0)
			(layer "F.Fab")
			(hide yes)
			(effects
				(font
					(size 1 1)
					(thickness 0.15)
				)
			)
		)
		(property "Voltage" "50V"
			(at 139.8 217.4 0)
			(layer "F.Fab")
			(hide yes)
			(effects
				(font
					(size 1 1)
					(thickness 0.15)
				)
			)
		)
		(sheetname "USB Debug, DP")
		(sheetfile "usb.kicad_sch")
		(attr smd)
		(fp_rect
			(start -0.925 -0.47)
			(end 0.925 0.47)
			(stroke
				(width 0.05)
				(type default)
			)
			(fill none)
			(layer "F.CrtYd")
		)
		(fp_line
			(start 0.504 0.248)
			(end -0.494 0.248)
			(stroke
				(width 0.15)
				(type solid)
			)
			(layer "F.Fab")
		)
		(fp_line
			(start 0.504 -0.25)
			(end 0.504 0.248)
			(stroke
				(width 0.15)
				(type solid)
			)
			(layer "F.Fab")
		)
		(fp_line
			(start -0.494 0.248)
			(end -0.494 -0.25)
			(stroke
				(width 0.15)
				(type solid)
			)
			(layer "F.Fab")
		)
		(fp_line
			(start -0.494 -0.25)
			(end 0.504 -0.25)
			(stroke
				(width 0.15)
				(type solid)
			)
			(layer "F.Fab")
		)
		(fp_text user "${REFERENCE}"
			(at -0.932 3.168 180)
			(layer "F.Fab")
			(hide yes)
			(effects
				(font
					(size 0.7 0.7)
					(thickness 0.15)
				)
				(justify left bottom)
			)
		)
		(fp_text user "Author: Antmicro"
			(at -0.932 4.17 180)
			(layer "F.Fab")
			(hide yes)
			(effects
				(font
					(size 0.7 0.7)
					(thickness 0.15)
				)
				(justify left bottom)
			)
		)
		(fp_text user "License: Apache-2.0"
			(at -0.932 5.17 180)
			(layer "F.Fab")
			(hide yes)
			(effects
				(font
					(size 0.7 0.7)
					(thickness 0.15)
				)
				(justify left bottom)
			)
		)
		(pad "1" smd roundrect
			(at -0.48 0 180)
			(size 0.59 0.64)
			(layers "F.Cu" "F.Paste" "F.Mask")
			(roundrect_rratio 0.25)
			(net 87 "+3V3")
			(pintype "passive")
		)
		(pad "2" smd roundrect
			(at 0.48 0 180)
			(size 0.59 0.64)
			(layers "F.Cu" "F.Paste" "F.Mask")
			(roundrect_rratio 0.25)
			(net 1 "GND")
			(pintype "passive")
		)
	)
)
